(kicad_pcb
	(version 20260206)
	(generator "pcbnew")
	(generator_version "10.0")
	(general
		(thickness 1.6)
		(legacy_teardrops no)
	)
	(paper "A4")
	(title_block
		(title "04192023_DAF0TMB3IC0_F0TG_MB_C_brd_V02_OCP.brd")
		(comment 1 "Grand Teton / footprints 2160-2164 of 8354")
	)
	(layers
		(0 "F.Cu" signal "TOP")
		(4 "In1.Cu" signal "GND")
		(6 "In2.Cu" signal "IN1")
		(8 "In3.Cu" signal "GND1")
		(10 "In4.Cu" signal "IN2")
		(12 "In5.Cu" signal "GND2")
		(14 "In6.Cu" signal "IN3")
		(16 "In7.Cu" signal "GND3")
		(18 "In8.Cu" signal "VCC")
		(20 "In9.Cu" signal "VCC1")
		(22 "In10.Cu" signal "GND4")
		(24 "In11.Cu" signal "IN4")
		(26 "In12.Cu" signal "GND5")
		(28 "In13.Cu" signal "IN5")
		(30 "In14.Cu" signal "GND6")
		(32 "In15.Cu" signal "IN6")
		(34 "In16.Cu" signal "GND7")
		(2 "B.Cu" signal "BOTTOM")
		(9 "F.Adhes" user "F.Adhesive")
		(11 "B.Adhes" user "B.Adhesive")
		(13 "F.Paste" user "Package Geometry/Pastemask Top")
		(15 "B.Paste" user "Package Geometry/Pastemask Bottom")
		(5 "F.SilkS" user "Ref Des/Silkscreen Top")
		(7 "B.SilkS" user "Ref Des/Silkscreen Bottom")
		(1 "F.Mask" user "Board Geometry/Soldermask Top")
		(3 "B.Mask" user "Board Geometry/Soldermask Bottom")
		(17 "Dwgs.User" user "User.Drawings")
		(19 "Cmts.User" user "User.Comments")
		(21 "Eco1.User" user "User.Eco1")
		(23 "Eco2.User" user "User.Eco2")
		(25 "Edge.Cuts" user "Board Geometry/Outline")
		(27 "Margin" user)
		(31 "F.CrtYd" user "Package Geometry/Place Bound Top")
		(29 "B.CrtYd" user "Package Geometry/Place Bound Bottom")
		(35 "F.Fab" user "Ref Des/Assembly Top")
		(33 "B.Fab" user "Ref Des/Assembly Bottom")
	)
	(footprint ""
		(layer "F.Cu")
		(at 326.667876 -70.098412 90)
		(property "Reference" "D75"
			(at -3.934714 -0.691642 90)
			(unlocked yes)
			(layer "F.SilkS")
			(effects
				(font
					(size 0.7874 0.5842)
					(thickness 0.1524)
				)
				(justify left)
			)
		)
		(property "Value" ""
			(at 0 0 90)
			(layer "F.Fab")
			(effects
				(font
					(size 1.27 1.27)
				)
			)
		)
		(duplicate_pad_numbers_are_jumpers no)
		(fp_line
			(start 1.16078 -0.4826)
			(end 1.16078 0.4826)
			(stroke
				(width 0.1524)
				(type default)
			)
			(layer "F.SilkS")
		)
		(fp_line
			(start 1.03378 -0.4826)
			(end 1.03378 0.4826)
			(stroke
				(width 0.1524)
				(type default)
			)
			(layer "F.SilkS")
		)
		(fp_line
			(start 0.90678 -0.4826)
			(end 0.90678 0.4826)
			(stroke
				(width 0.1524)
				(type default)
			)
			(layer "F.SilkS")
		)
		(fp_line
			(start -0.64008 -0.4826)
			(end 1.16078 -0.4826)
			(stroke
				(width 0.1524)
				(type default)
			)
			(layer "F.SilkS")
		)
		(fp_line
			(start -0.79248 -0.4826)
			(end 1.03378 -0.4826)
			(stroke
				(width 0.1524)
				(type default)
			)
			(layer "F.SilkS")
		)
		(fp_line
			(start -0.89408 -0.4826)
			(end 0.90678 -0.4826)
			(stroke
				(width 0.1524)
				(type default)
			)
			(layer "F.SilkS")
		)
		(fp_line
			(start 1.16078 0.4826)
			(end -0.64008 0.4826)
			(stroke
				(width 0.1524)
				(type default)
			)
			(layer "F.SilkS")
		)
		(fp_line
			(start 1.03378 0.4826)
			(end -0.79248 0.4826)
			(stroke
				(width 0.1524)
				(type default)
			)
			(layer "F.SilkS")
		)
		(fp_line
			(start 0.90678 0.4826)
			(end -0.90678 0.4826)
			(stroke
				(width 0.1524)
				(type default)
			)
			(layer "F.SilkS")
		)
		(fp_line
			(start -0.90678 0.4826)
			(end -0.90678 -0.4699)
			(stroke
				(width 0.1524)
				(type default)
			)
			(layer "F.SilkS")
		)
		(fp_line
			(start 0.499872 -0.249936)
			(end 0.499872 0.249936)
			(stroke
				(width 0.1)
				(type default)
			)
			(layer "F.Fab")
		)
		(fp_line
			(start -0.499872 -0.249936)
			(end 0.499872 -0.249936)
			(stroke
				(width 0.1)
				(type default)
			)
			(layer "F.Fab")
		)
		(fp_line
			(start 0.499872 0.249936)
			(end -0.499872 0.249936)
			(stroke
				(width 0.1)
				(type default)
			)
			(layer "F.Fab")
		)
		(fp_line
			(start -0.499872 0.249936)
			(end -0.499872 -0.249936)
			(stroke
				(width 0.1)
				(type default)
			)
			(layer "F.Fab")
		)
		(pad "A" smd rect
			(at -0.47498 0 90)
			(size 0.6096 0.7112)
			(layers "F.Cu" "F.Mask" "F.Paste")
			(net "LED_PWRGD_PVDDCR_SOC_P0_R")
		)
		(pad "C" smd rect
			(at 0.47498 0 90)
			(size 0.6096 0.7112)
			(layers "F.Cu" "F.Mask" "F.Paste")
			(net "LED_PWRGD_PVDDCR_SOC_P0_D")
		)
	)
	(footprint ""
		(layer "F.Cu")
		(at 320.572384 -341.042244 180)
		(property "Reference" "PC116_3"
			(at 0 0 180)
			(layer "F.SilkS")
			(hide yes)
			(effects
				(font
					(size 1.27 1.27)
				)
			)
		)
		(property "Value" ""
			(at 0 0 180)
			(layer "F.Fab")
			(effects
				(font
					(size 1.27 1.27)
				)
			)
		)
		(duplicate_pad_numbers_are_jumpers no)
		(fp_line
			(start 0.7874 0.4064)
			(end -0.7874 0.4064)
			(stroke
				(width 0.1524)
				(type default)
			)
			(layer "F.SilkS")
		)
		(fp_line
			(start 0.7874 -0.4064)
			(end 0.7874 0.4064)
			(stroke
				(width 0.1524)
				(type default)
			)
			(layer "F.SilkS")
		)
		(fp_line
			(start -0.7874 0.4064)
			(end -0.7874 -0.4064)
			(stroke
				(width 0.1524)
				(type default)
			)
			(layer "F.SilkS")
		)
		(fp_line
			(start -0.7874 -0.4064)
			(end 0.7874 -0.4064)
			(stroke
				(width 0.1524)
				(type default)
			)
			(layer "F.SilkS")
		)
		(fp_line
			(start 0.67945 0.3048)
			(end 0.120396 0.3048)
			(stroke
				(width 0.1)
				(type default)
			)
			(layer "F.Fab")
		)
		(fp_line
			(start 0.67945 -0.3048)
			(end 0.67945 0.3048)
			(stroke
				(width 0.1)
				(type default)
			)
			(layer "F.Fab")
		)
		(fp_line
			(start 0.12065 -0.2794)
			(end 0.12065 -0.3048)
			(stroke
				(width 0.1)
				(type default)
			)
			(layer "F.Fab")
		)
		(fp_line
			(start 0.12065 -0.3048)
			(end 0.67945 -0.3048)
			(stroke
				(width 0.1)
				(type default)
			)
			(layer "F.Fab")
		)
		(fp_line
			(start 0.120396 0.3048)
			(end 0.120396 0.2794)
			(stroke
				(width 0.1)
				(type default)
			)
			(layer "F.Fab")
		)
		(fp_line
			(start 0.120396 0.2794)
			(end -0.12065 0.2794)
			(stroke
				(width 0.1)
				(type default)
			)
			(layer "F.Fab")
		)
		(fp_line
			(start -0.12065 0.3048)
			(end -0.67945 0.3048)
			(stroke
				(width 0.1)
				(type default)
			)
			(layer "F.Fab")
		)
		(fp_line
			(start -0.12065 0.2794)
			(end -0.12065 0.3048)
			(stroke
				(width 0.1)
				(type default)
			)
			(layer "F.Fab")
		)
		(fp_line
			(start -0.12065 -0.2794)
			(end 0.12065 -0.2794)
			(stroke
				(width 0.1)
				(type default)
			)
			(layer "F.Fab")
		)
		(fp_line
			(start -0.12065 -0.305054)
			(end -0.12065 -0.2794)
			(stroke
				(width 0.1)
				(type default)
			)
			(layer "F.Fab")
		)
		(fp_line
			(start -0.67945 0.3048)
			(end -0.67945 -0.305054)
			(stroke
				(width 0.1)
				(type default)
			)
			(layer "F.Fab")
		)
		(fp_line
			(start -0.67945 -0.305054)
			(end -0.12065 -0.305054)
			(stroke
				(width 0.1)
				(type default)
			)
			(layer "F.Fab")
		)
		(pad "1" smd circle
			(at -0.40005 0 180)
			(size 0 0)
			(layers "F.Cu" "F.Mask" "F.Paste")
			(net "SW_P12V_AUX_PVDDCR_CPU1_P0_FLT")
		)
		(pad "2" smd circle
			(at 0.40005 0 180)
			(size 0 0)
			(layers "F.Cu" "F.Mask" "F.Paste")
			(net "GND")
		)
	)
	(footprint ""
		(layer "F.Cu")
		(at 111.149892 -181.176168)
		(property "Reference" "PC317"
			(at 0 0 0)
			(layer "F.SilkS")
			(hide yes)
			(effects
				(font
					(size 1.27 1.27)
				)
			)
		)
		(property "Value" ""
			(at 0 0 0)
			(layer "F.Fab")
			(effects
				(font
					(size 1.27 1.27)
				)
			)
		)
		(duplicate_pad_numbers_are_jumpers no)
		(fp_line
			(start -0.7874 -0.4064)
			(end 0.7874 -0.4064)
			(stroke
				(width 0.1524)
				(type default)
			)
			(layer "F.SilkS")
		)
		(fp_line
			(start -0.7874 0.4064)
			(end -0.7874 -0.4064)
			(stroke
				(width 0.1524)
				(type default)
			)
			(layer "F.SilkS")
		)
		(fp_line
			(start 0.7874 -0.4064)
			(end 0.7874 0.4064)
			(stroke
				(width 0.1524)
				(type default)
			)
			(layer "F.SilkS")
		)
		(fp_line
			(start 0.7874 0.4064)
			(end -0.7874 0.4064)
			(stroke
				(width 0.1524)
				(type default)
			)
			(layer "F.SilkS")
		)
		(fp_line
			(start -0.67945 -0.305054)
			(end -0.12065 -0.305054)
			(stroke
				(width 0.1)
				(type default)
			)
			(layer "F.Fab")
		)
		(fp_line
			(start -0.67945 0.3048)
			(end -0.67945 -0.305054)
			(stroke
				(width 0.1)
				(type default)
			)
			(layer "F.Fab")
		)
		(fp_line
			(start -0.12065 -0.305054)
			(end -0.12065 -0.2794)
			(stroke
				(width 0.1)
				(type default)
			)
			(layer "F.Fab")
		)
		(fp_line
			(start -0.12065 -0.2794)
			(end 0.12065 -0.2794)
			(stroke
				(width 0.1)
				(type default)
			)
			(layer "F.Fab")
		)
		(fp_line
			(start -0.12065 0.2794)
			(end -0.12065 0.3048)
			(stroke
				(width 0.1)
				(type default)
			)
			(layer "F.Fab")
		)
		(fp_line
			(start -0.12065 0.3048)
			(end -0.67945 0.3048)
			(stroke
				(width 0.1)
				(type default)
			)
			(layer "F.Fab")
		)
		(fp_line
			(start 0.120396 0.2794)
			(end -0.12065 0.2794)
			(stroke
				(width 0.1)
				(type default)
			)
			(layer "F.Fab")
		)
		(fp_line
			(start 0.120396 0.3048)
			(end 0.120396 0.2794)
			(stroke
				(width 0.1)
				(type default)
			)
			(layer "F.Fab")
		)
		(fp_line
			(start 0.12065 -0.3048)
			(end 0.67945 -0.3048)
			(stroke
				(width 0.1)
				(type default)
			)
			(layer "F.Fab")
		)
		(fp_line
			(start 0.12065 -0.2794)
			(end 0.12065 -0.3048)
			(stroke
				(width 0.1)
				(type default)
			)
			(layer "F.Fab")
		)
		(fp_line
			(start 0.67945 -0.3048)
			(end 0.67945 0.3048)
			(stroke
				(width 0.1)
				(type default)
			)
			(layer "F.Fab")
		)
		(fp_line
			(start 0.67945 0.3048)
			(end 0.120396 0.3048)
			(stroke
				(width 0.1)
				(type default)
			)
			(layer "F.Fab")
		)
		(pad "1" smd circle
			(at -0.40005 0)
			(size 0 0)
			(layers "F.Cu" "F.Mask" "F.Paste")
			(net "SW_PVDDCR_CPU0_P1_SW4")
		)
		(pad "2" smd circle
			(at 0.40005 0)
			(size 0 0)
			(layers "F.Cu" "F.Mask" "F.Paste")
			(net "SW_PVDDCR_CPU0_P1_SW4_RC")
		)
	)
	(footprint ""
		(layer "F.Cu")
		(at 258.99237 -132.980176 180)
		(property "Reference" "U53"
			(at 1.11506 -3.372104 0)
			(unlocked yes)
			(layer "F.SilkS")
			(effects
				(font
					(size 0.7874 0.5842)
					(thickness 0.1524)
				)
				(justify left)
			)
		)
		(property "Value" ""
			(at 0 0 180)
			(layer "F.Fab")
			(effects
				(font
					(size 1.27 1.27)
				)
			)
		)
		(duplicate_pad_numbers_are_jumpers no)
		(fp_line
			(start 1.868932 2.549906)
			(end 1.868932 -2.549906)
			(stroke
				(width 0.1524)
				(type default)
			)
			(layer "F.SilkS")
		)
		(fp_line
			(start 1.868932 -2.549906)
			(end 1.025906 -2.549906)
			(stroke
				(width 0.1524)
				(type default)
			)
			(layer "F.SilkS")
		)
		(fp_line
			(start 1.025906 -2.549906)
			(end 0 -1.524)
			(stroke
				(width 0.1524)
				(type default)
			)
			(layer "F.SilkS")
		)
		(fp_line
			(start 0 -1.524)
			(end -1.025906 -2.549906)
			(stroke
				(width 0.1524)
				(type default)
			)
			(layer "F.SilkS")
		)
		(fp_line
			(start -1.025906 -2.549906)
			(end -1.868932 -2.549906)
			(stroke
				(width 0.1524)
				(type default)
			)
			(layer "F.SilkS")
		)
		(fp_line
			(start -1.868932 2.549906)
			(end 1.868932 2.549906)
			(stroke
				(width 0.1524)
				(type default)
			)
			(layer "F.SilkS")
		)
		(fp_line
			(start -1.868932 -2.549906)
			(end -1.868932 2.549906)
			(stroke
				(width 0.1524)
				(type default)
			)
			(layer "F.SilkS")
		)
		(fp_poly
			(pts
				(xy -2.802128 -2.775966) (xy -3.310128 -3.791966) (xy -2.294128 -3.791966)
			)
			(stroke
				(width 0)
				(type default)
			)
			(fill yes)
			(layer "F.SilkS")
		)
		(fp_line
			(start 2.249932 2.549906)
			(end 2.249932 -2.549906)
			(stroke
				(width 0.1)
				(type default)
			)
			(layer "F.Fab")
		)
		(fp_line
			(start 2.249932 -2.549906)
			(end -2.249932 -2.549906)
			(stroke
				(width 0.1)
				(type default)
			)
			(layer "F.Fab")
		)
		(fp_line
			(start -2.249932 2.549906)
			(end 2.249932 2.549906)
			(stroke
				(width 0.1)
				(type default)
			)
			(layer "F.Fab")
		)
		(fp_line
			(start -2.249932 -2.549906)
			(end -2.249932 2.549906)
			(stroke
				(width 0.1)
				(type default)
			)
			(layer "F.Fab")
		)
		(fp_poly
			(pts
				(xy -4.7752 -1.787398) (xy -4.7752 -2.803398) (xy -3.7592 -2.295398)
			)
			(stroke
				(width 0)
				(type default)
			)
			(fill yes)
			(layer "F.Fab")
		)
		(pad "1" smd rect
			(at -2.800096 -2.275078 90)
			(size 0.3556 1.6002)
			(layers "F.Cu" "F.Mask" "F.Paste")
			(net "PVDD18_S5_P0")
		)
		(pad "2" smd rect
			(at -2.800096 -1.625092 90)
			(size 0.3556 1.6002)
			(layers "F.Cu" "F.Mask" "F.Paste")
			(net "PVDD18_S5_P0")
		)
		(pad "3" smd rect
			(at -2.800096 -0.975106 90)
			(size 0.3556 1.6002)
			(layers "F.Cu" "F.Mask" "F.Paste")
			(net "SPI_CPU0_CS0_N")
		)
		(pad "4" smd rect
			(at -2.800096 -0.32512 90)
			(size 0.3556 1.6002)
			(layers "F.Cu" "F.Mask" "F.Paste")
			(net "SPI_CPU0_CLK")
		)
		(pad "5" smd rect
			(at -2.800096 0.32512 90)
			(size 0.3556 1.6002)
			(layers "F.Cu" "F.Mask" "F.Paste")
			(net "SPI_CPU0_CS1_N")
		)
		(pad "6" smd rect
			(at -2.800096 0.975106 90)
			(size 0.3556 1.6002)
			(layers "F.Cu" "F.Mask" "F.Paste")
			(net "SPI_CPU0_TPM_CS_N")
		)
		(pad "7" smd rect
			(at -2.800096 1.625092 90)
			(size 0.3556 1.6002)
			(layers "F.Cu" "F.Mask" "F.Paste")
			(net "PVDD18_S5_P0")
		)
		(pad "8" smd rect
			(at -2.800096 2.275078 90)
			(size 0.3556 1.6002)
			(layers "F.Cu" "F.Mask" "F.Paste")
			(net "PVDD18_S5_P0")
		)
		(pad "9" smd rect
			(at 2.800096 2.275078 90)
			(size 0.3556 1.6002)
			(layers "F.Cu" "F.Mask" "F.Paste")
			(net "ROM_SD_LS_OE")
		)
		(pad "10" smd rect
			(at 2.800096 1.625092 90)
			(size 0.3556 1.6002)
			(layers "F.Cu" "F.Mask" "F.Paste")
			(net "GND")
		)
		(pad "11" smd rect
			(at 2.800096 0.975106 90)
			(size 0.3556 1.6002)
			(layers "F.Cu" "F.Mask" "F.Paste")
			(net "SPI_CPU0_LVC3_R_TPM_CS_N")
		)
		(pad "12" smd rect
			(at 2.800096 0.32512 90)
			(size 0.3556 1.6002)
			(layers "F.Cu" "F.Mask" "F.Paste")
			(net "SPI_CPU0_LVC3_CS1_N")
		)
		(pad "13" smd rect
			(at 2.800096 -0.32512 90)
			(size 0.3556 1.6002)
			(layers "F.Cu" "F.Mask" "F.Paste")
			(net "SPI_CPU0_LVC3_CLK")
		)
		(pad "14" smd rect
			(at 2.800096 -0.975106 90)
			(size 0.3556 1.6002)
			(layers "F.Cu" "F.Mask" "F.Paste")
			(net "SPI_CPU0_LVC3_CS0_N")
		)
		(pad "15" smd rect
			(at 2.800096 -1.625092 90)
			(size 0.3556 1.6002)
			(layers "F.Cu" "F.Mask" "F.Paste")
			(net "P3V3_AUX")
		)
		(pad "16" smd rect
			(at 2.800096 -2.275078 90)
			(size 0.3556 1.6002)
			(layers "F.Cu" "F.Mask" "F.Paste")
			(net "PVDD18_S5_P0")
		)
	)
	(footprint ""
		(layer "F.Cu")
		(at 150.368762 -120.485662 180)
		(property "Reference" "R2222"
			(at 0 0 180)
			(layer "F.SilkS")
			(hide yes)
			(effects
				(font
					(size 1.27 1.27)
				)
			)
		)
		(property "Value" ""
			(at 0 0 180)
			(layer "F.Fab")
			(effects
				(font
					(size 1.27 1.27)
				)
			)
		)
		(duplicate_pad_numbers_are_jumpers no)
		(fp_line
			(start 0.7874 0.4064)
			(end -0.7874 0.4064)
			(stroke
				(width 0.1524)
				(type default)
			)
			(layer "F.SilkS")
		)
		(fp_line
			(start 0.7874 -0.4064)
			(end 0.7874 0.4064)
			(stroke
				(width 0.1524)
				(type default)
			)
			(layer "F.SilkS")
		)
		(fp_line
			(start -0.7874 0.4064)
			(end -0.7874 -0.4064)
			(stroke
				(width 0.1524)
				(type default)
			)
			(layer "F.SilkS")
		)
		(fp_line
			(start -0.7874 -0.4064)
			(end 0.7874 -0.4064)
			(stroke
				(width 0.1524)
				(type default)
			)
			(layer "F.SilkS")
		)
		(fp_line
			(start 0.67945 0.3048)
			(end 0.120396 0.3048)
			(stroke
				(width 0.1)
				(type default)
			)
			(layer "F.Fab")
		)
		(fp_line
			(start 0.67945 -0.3048)
			(end 0.67945 0.3048)
			(stroke
				(width 0.1)
				(type default)
			)
			(layer "F.Fab")
		)
		(fp_line
			(start 0.12065 -0.2794)
			(end 0.12065 -0.3048)
			(stroke
				(width 0.1)
				(type default)
			)
			(layer "F.Fab")
		)
		(fp_line
			(start 0.12065 -0.3048)
			(end 0.67945 -0.3048)
			(stroke
				(width 0.1)
				(type default)
			)
			(layer "F.Fab")
		)
		(fp_line
			(start 0.120396 0.3048)
			(end 0.120396 0.2794)
			(stroke
				(width 0.1)
				(type default)
			)
			(layer "F.Fab")
		)
		(fp_line
			(start 0.120396 0.2794)
			(end -0.12065 0.2794)
			(stroke
				(width 0.1)
				(type default)
			)
			(layer "F.Fab")
		)
		(fp_line
			(start -0.12065 0.3048)
			(end -0.67945 0.3048)
			(stroke
				(width 0.1)
				(type default)
			)
			(layer "F.Fab")
		)
		(fp_line
			(start -0.12065 0.2794)
			(end -0.12065 0.3048)
			(stroke
				(width 0.1)
				(type default)
			)
			(layer "F.Fab")
		)
		(fp_line
			(start -0.12065 -0.2794)
			(end 0.12065 -0.2794)
			(stroke
				(width 0.1)
				(type default)
			)
			(layer "F.Fab")
		)
		(fp_line
			(start -0.12065 -0.305054)
			(end -0.12065 -0.2794)
			(stroke
				(width 0.1)
				(type default)
			)
			(layer "F.Fab")
		)
		(fp_line
			(start -0.67945 0.3048)
			(end -0.67945 -0.305054)
			(stroke
				(width 0.1)
				(type default)
			)
			(layer "F.Fab")
		)
		(fp_line
			(start -0.67945 -0.305054)
			(end -0.12065 -0.305054)
			(stroke
				(width 0.1)
				(type default)
			)
			(layer "F.Fab")
		)
		(pad "1" smd circle
			(at -0.40005 0 180)
			(size 0 0)
			(layers "F.Cu" "F.Mask" "F.Paste")
			(net "A_P12V_STBY_FP_TRIGGER")
		)
		(pad "2" smd circle
			(at 0.40005 0 180)
			(size 0 0)
			(layers "F.Cu" "F.Mask" "F.Paste")
			(net "GND")
		)
	)
)
